# BASEBOARD_FAB2 (Tioga Pass) — schematic netlist excerpt (pin names and nets, part order shuffled) for the footprints in the layout excerpt that follows; sources: Cadence DE-HDL packaged netlist, KiCad conversion of Wiwynn_Tioga_Pass_MB.brd

EU7A4  IR354XX  IR35411 IC  pkg SM  page 219
  VOS  = PVDDQ_DEF
  LGND  = GND
  VCC  = VR_PVDDQ_DEF_PH2_VCIN
  VDRV  = P5V_STBY
  PGND(0)  = GND
  GL(0)  = TP_PVDDQ_DEF_PH2_GL_0
  PGND(1)  = GND
  SW  = VR_PVDDQ_DEF_PH2_SW
  VIN(0)  = VR_FET_SW_P12V_STBY_PVDDQ_DEF
  VIN(1)  = VR_FET_SW_P12V_STBY_PVDDQ_DEF
  NC  = NC
  PHASE  = VR_PVDDQ_DEF_PH2_PHASE
  BOOST  = VR_PVDDQ_DEF_PH2_BOOT_R
  PWM  = VR_PVDDQ_DEF_PWM2
  EN  = P5V_STBY
  TOUT_FLT  = A_TSENSE_PVDDQ_DEF
  OCSET  = VR_PVDDQ_DEF_PH2_OCSET
  IOUT  = ISENSE_PVDDQ_DEF_PH2_IMON
  REFIN  = VR_PVDDQ_DEF_AIREF2
  PGND(2)  = GND
  GL(1)  = TP_PVDDQ_DEF_PH2_GL_1

(kicad_pcb
	(version 20260206)
	(generator "pcbnew")
	(generator_version "10.0")
	(general
		(thickness 1.6)
		(legacy_teardrops no)
	)
	(paper "A4")
	(title_block
		(title "Wiwynn_Tioga_Pass_MB.brd")
		(comment 1 "Tioga Pass / footprints 1213-1213 of 4770")
	)
	(layers
		(0 "F.Cu" signal "TOP")
		(4 "In1.Cu" signal "L2GND")
		(6 "In2.Cu" signal "L3")
		(8 "In3.Cu" signal "L4GND")
		(10 "In4.Cu" signal "L5")
		(12 "In5.Cu" signal "L6GND")
		(14 "In6.Cu" signal "L7VCC")
		(16 "In7.Cu" signal "L8VCC")
		(18 "In8.Cu" signal "L9GND")
		(20 "In9.Cu" signal "L10")
		(22 "In10.Cu" signal "L11GND")
		(24 "In11.Cu" signal "L12")
		(26 "In12.Cu" signal "L13GND")
		(2 "B.Cu" signal "BOTTOM")
		(9 "F.Adhes" user "F.Adhesive")
		(11 "B.Adhes" user "B.Adhesive")
		(13 "F.Paste" user "Package Geometry/Pastemask Top")
		(15 "B.Paste" user "Package Geometry/Pastemask Bottom")
		(5 "F.SilkS" user "Ref Des/Silkscreen Top")
		(7 "B.SilkS" user "Ref Des/Silkscreen Bottom")
		(1 "F.Mask" user "Board Geometry/Soldermask Top")
		(3 "B.Mask" user "Board Geometry/Soldermask Bottom")
		(17 "Dwgs.User" user "User.Drawings")
		(19 "Cmts.User" user "User.Comments")
		(21 "Eco1.User" user "User.Eco1")
		(23 "Eco2.User" user "User.Eco2")
		(25 "Edge.Cuts" user "Board Geometry/Outline")
		(27 "Margin" user)
		(31 "F.CrtYd" user "Package Geometry/Place Bound Top")
		(29 "B.CrtYd" user "Package Geometry/Place Bound Bottom")
		(35 "F.Fab" user "Ref Des/Assembly Top")
		(33 "B.Fab" user "Ref Des/Assembly Bottom")
	)
	(footprint ""
		(layer "F.Cu")
		(at 347.462094 -145.293842 -90)
		(property "Reference" "EU7A4"
			(at 5.874512 -1.483106 0)
			(unlocked yes)
			(layer "F.SilkS")
			(effects
				(font
					(size 0.7874 0.5842)
					(thickness 0.1524)
				)
			)
		)
		(property "Value" ""
			(at 0 0 270)
			(layer "F.Fab")
			(effects
				(font
					(size 1.27 1.27)
				)
			)
		)
		(duplicate_pad_numbers_are_jumpers no)
		(fp_line
			(start -3.0099 3.429)
			(end -3.0099 -3.5052)
			(stroke
				(width 0.1524)
				(type default)
			)
			(layer "F.SilkS")
		)
		(fp_line
			(start 2.9718 3.429)
			(end -3.0099 3.429)
			(stroke
				(width 0.1524)
				(type default)
			)
			(layer "F.SilkS")
		)
		(fp_line
			(start -3.0099 -3.5052)
			(end 2.9718 -3.5052)
			(stroke
				(width 0.1524)
				(type default)
			)
			(layer "F.SilkS")
		)
		(fp_line
			(start 2.9718 -3.5052)
			(end 2.9718 3.429)
			(stroke
				(width 0.1524)
				(type default)
			)
			(layer "F.SilkS")
		)
		(fp_circle
			(center -3.736848 -3.271266)
			(end -3.736848 -3.398266)
			(stroke
				(width 0.254)
				(type default)
			)
			(fill no)
			(layer "F.SilkS")
		)
		(fp_poly
			(pts
				(xy -2.9972 -3.4925) (xy -2.9972 -2.6924) (xy -2.1971 -3.4925)
			)
			(stroke
				(width 0)
				(type default)
			)
			(fill yes)
			(layer "F.SilkS")
		)
		(fp_poly
			(pts
				(xy -2.549906 -3.050032) (xy -2.549906 3.050032) (xy 2.549906 3.050032) (xy 2.549906 -3.050032)
			)
			(stroke
				(width 0)
				(type default)
			)
			(fill no)
			(layer "F.CrtYd")
		)
		(fp_line
			(start -2.549906 3.050032)
			(end -2.549906 -3.050032)
			(stroke
				(width 0.1)
				(type default)
			)
			(layer "F.Fab")
		)
		(fp_line
			(start 2.549906 3.050032)
			(end -2.549906 3.050032)
			(stroke
				(width 0.1)
				(type default)
			)
			(layer "F.Fab")
		)
		(fp_line
			(start -2.549906 -3.050032)
			(end 2.549906 -3.050032)
			(stroke
				(width 0.1)
				(type default)
			)
			(layer "F.Fab")
		)
		(fp_line
			(start 2.549906 -3.050032)
			(end 2.549906 3.050032)
			(stroke
				(width 0.1)
				(type default)
			)
			(layer "F.Fab")
		)
		(fp_circle
			(center -3.057398 -2.678684)
			(end -3.057398 -2.805684)
			(stroke
				(width 0.254)
				(type default)
			)
			(fill no)
			(layer "F.Fab")
		)
		(pad "1" smd rect
			(at -2.39522 -2.279904 270)
			(size 0.7112 0.254)
			(layers "F.Cu" "F.Mask" "F.Paste")
			(net "PVDDQ_DEF")
		)
		(pad "2" smd rect
			(at -2.39522 -1.83007 270)
			(size 0.7112 0.254)
			(layers "F.Cu" "F.Mask" "F.Paste")
			(net "GND")
		)
		(pad "3" smd rect
			(at -2.39522 -1.379982 270)
			(size 0.7112 0.254)
			(layers "F.Cu" "F.Mask" "F.Paste")
			(net "VR_PVDDQ_DEF_PH2_VCIN")
		)
		(pad "4" smd rect
			(at -2.39522 -0.929894 270)
			(size 0.7112 0.254)
			(layers "F.Cu" "F.Mask" "F.Paste")
			(net "P5V_STBY")
		)
		(pad "5" smd rect
			(at -2.39522 -0.48006 270)
			(size 0.7112 0.254)
			(layers "F.Cu" "F.Mask" "F.Paste")
			(net "GND")
		)
		(pad "6" smd rect
			(at -2.39522 -0.029972 270)
			(size 0.7112 0.254)
			(layers "F.Cu" "F.Mask" "F.Paste")
			(net "TP_PVDDQ_DEF_PH2_GL_0")
		)
		(pad "7" smd custom
			(at 0.016764 1.145032 270)
			(size 0.53975 0.53975)
			(layers "F.Cu" "F.Mask" "F.Paste")
			(net "GND")
			(options
				(clearance outline)
				(anchor circle)
			)
			(primitives
				(gr_poly
					(pts
						(xy -2.7051 1.0795) (xy -2.7051 -0.3683) (xy -0.9271 -0.3683) (xy -0.9271 -1.0795) (xy 2.7051 -1.0795)
						(xy 2.7051 1.0795)
					)
					(width 0)
					(fill yes)
				)
			)
		)
		(pad "10" smd rect
			(at -0.008382 2.874772 270)
			(size 4.3434 0.6096)
			(layers "F.Cu" "F.Mask" "F.Paste")
			(net "VR_PVDDQ_DEF_PH2_SW")
		)
		(pad "25" smd rect
			(at 1.548384 -1.283208 270)
			(size 2.3368 2.0066)
			(layers "F.Cu" "F.Mask" "F.Paste")
			(net "VR_FET_SW_P12V_STBY_PVDDQ_DEF")
		)
		(pad "30" smd rect
			(at 2.050034 -2.895092 270)
			(size 0.254 0.7112)
			(layers "F.Cu" "F.Mask" "F.Paste")
			(net "VR_FET_SW_P12V_STBY_PVDDQ_DEF")
		)
		(pad "31" smd rect
			(at 1.599946 -2.895092 270)
			(size 0.254 0.7112)
			(layers "F.Cu" "F.Mask" "F.Paste")
			(net "Net_371")
		)
		(pad "32" smd rect
			(at 1.150112 -2.895092 270)
			(size 0.254 0.7112)
			(layers "F.Cu" "F.Mask" "F.Paste")
			(net "VR_PVDDQ_DEF_PH2_PHASE")
		)
		(pad "33" smd rect
			(at 0.700024 -2.895092 270)
			(size 0.254 0.7112)
			(layers "F.Cu" "F.Mask" "F.Paste")
			(net "VR_PVDDQ_DEF_PH2_BOOT_R")
		)
		(pad "34" smd rect
			(at 0.249936 -2.895092 270)
			(size 0.254 0.7112)
			(layers "F.Cu" "F.Mask" "F.Paste")
			(net "VR_PVDDQ_DEF_PWM2")
		)
		(pad "35" smd rect
			(at -0.199898 -2.895092 270)
			(size 0.254 0.7112)
			(layers "F.Cu" "F.Mask" "F.Paste")
			(net "P5V_STBY")
		)
		(pad "36" smd rect
			(at -0.649986 -2.895092 270)
			(size 0.254 0.7112)
			(layers "F.Cu" "F.Mask" "F.Paste")
			(net "A_TSENSE_PVDDQ_DEF")
		)
		(pad "37" smd rect
			(at -1.100074 -2.895092 270)
			(size 0.254 0.7112)
			(layers "F.Cu" "F.Mask" "F.Paste")
			(net "VR_PVDDQ_DEF_PH2_OCSET")
		)
		(pad "38" smd rect
			(at -1.549908 -2.895092 270)
			(size 0.254 0.7112)
			(layers "F.Cu" "F.Mask" "F.Paste")
			(net "ISENSE_PVDDQ_DEF_PH2_IMON")
		)
		(pad "39" smd rect
			(at -1.999996 -2.895092 270)
			(size 0.254 0.7112)
			(layers "F.Cu" "F.Mask" "F.Paste")
			(net "VR_PVDDQ_DEF_AIREF2")
		)
		(pad "40" smd rect
			(at -0.871728 -1.283208 270)
			(size 1.8034 2.0066)
			(layers "F.Cu" "F.Mask" "F.Paste")
			(net "GND")
		)
		(pad "41" smd rect
			(at -1.533906 0.247904 270)
			(size 0.508 0.3556)
			(layers "F.Cu" "F.Mask" "F.Paste")
			(net "TP_PVDDQ_DEF_PH2_GL_1")
		)
	)
)
